 
. 
 
 
OCP-TAP 
Receiver Carrier Board (RCB) 
Form-Factor 
 
Version 0.1 
 
Hardware Specification 
 
 
Author: <name>



Open Compute Project   •   TAP Receiver Carrier Board (RCB) 
Date:  January 2023         Page 2 
 
Table of Contents 
1. Overview .................................................................................................................................. 3 
1.1. Acronyms.......................................................................................................................... 4 
2. Scope ....................................................................................................................................... 4 
3. License..................................................................................................................................... 4 
3.1. Open Web Foundation (OWF) CLA ................................................................................. 4 
3.2. Acknowledgements .......................................................................................................... 5 
4. Compliance with OCP Tenets ................................................................................................. 6 
4.1. Openness ......................................................................................................................... 6 
4.2. Efficiency .......................................................................................................................... 6 
4.3. Impact ............................................................................................................................... 6 
4.4. Scale ................................................................................................................................. 6 
5. Physical Specifications ........................................................................................................ 7 
5.1. I/O ..................................................................................................................................... 7 
5.2. Board Connector – Pinout ................................................................................................ 7 
5.3. Mechanical ....................................................................................................................... 7 
5.3.1. Bottom View .................................................................................................................. 8 
5.3.2. Side View ...................................................................................................................... 8 
6. Hardware Management ....................................................................................................... 8 
7. Version Table ....................................................................................................................... 8 
8. References ........................................................................................................................... 9 
Appendix A  - Checklist  for IC approval  of this Specification (to be completed by contributor(s) 
of this Spec) .................................................................................................................................. 11 
Appendix B-__ <supplier name>  - OCP Supplier Information and Hardware Product 
Recognition Checklist ................................................................................................................... 12 
Appendix C -  Contribution Process FAQs ................................................................................... 14 
 
 
  



Open Compute Project   •   TAP Receiver Carrier Board (RCB) 
Date:  January 2023         Page 3 
1. Overview 
The Receiver Carrier Board (RCB) is a GNSS receiver module that provides PPS output and 
the TOD to the Time Card. 
 
The OCP-TAP RCB form factor standardizes the dimensions, layout and connectivity of modular 
GNSS receivers for OCP-TAP Time Cards. 
 
A standard modular RCB Form Factor allows Time Card customers to interchange and upgrade 
GNSS receivers with ease, and lets manufacturers an easier path to release new and improved 
GNSS receiver that are compatible with OCP-TAP Time Cards.  
 
The RCB Form Factor can lead to a faster pace of innovation and development as 
manufacturers can focus on creating new components rather than iterating on the Time Servers, 
Time Cards and NICs for each new product or revision.  
 
 
Figure 1 - Time-Card with RCB 
 
 
Figure 2 - Receiver Carrier Board (RCB) 
  


Open Compute Project   •   TAP Receiver Carrier Board (RCB) 
Date:  January 2023         Page 4 
1.1. Acronyms  
Abbreviation Definition  
GNSS Global Navigation Satellite System 
RCB Receiver Carrier Board 
TAP Time Appliance Project 
PPS Pulse Per Second  
ToD Time of Day 
NIC Network Interface Card 
PTP  Precision Time Protocol  
 
2. Scope 
This document defines the technical details for base specification for Receiver Carrier Board 
(RCB).    
Any supplier seeking OCP recognition for a hardware product based on this Specification must 
be 100% compliant with all features or requirements described  
3. License 
3.1. Open Web Foundation (OWF) CLA 
Contributions to this Specification are made under the terms and conditions set forth in Open 
Web Foundation Modified Contributor License Agreement (“OWF CLA 1.0”) (“Contribution 
License”) by:  
Meta, NVIDIA 
 
Usage of this Specification is governed by the terms and conditions set forth in Open Web 
Foundation Modified Final Specification Agreement (“OWFa 1.0”) (“Specification 
License”).    
 
You can review the applicable OWFa1.0 Specification License(s) referenced above by the 
contributors to this Specification on the OCP website at 
http://www.opencompute.org/participate/legal-documents/. For actual executed copies of either 
agreement, please contact OCP directly. 
 
 Notes:  
 
1. The above license does not apply to the Appendix or Appendices. The information in the 
Appendix or Appendices is for reference only and non-normative in nature.  
 
NOTWITHSTANDING THE FOREGOING LICENSES, THIS SPECIFICATION IS PROVIDED 
BY OCP "AS IS" AND OCP EXPRESSLY DISCLAIMS ANY WARRANTIES (EXPRESS, 
IMPLIED, OR OTHERWISE), INCLUDING IMPLIED WARRANTIES OF MERCHANTABILITY, 
NON-INFRINGEMENT, FITNESS FOR A PARTICULAR PURPOSE, OR TITLE, RELATED TO 
THE SPECIFICATION. NOTICE IS HEREBY GIVEN, THAT OTHER RIGHTS NOT GRANTED 



Open Compute Project   •   TAP Receiver Carrier Board (RCB) 
Date:  January 2023         Page 5 
AS SET FORTH ABOVE, INCLUDING WITHOUT LIMITATION, RIGHTS OF THIRD PARTIES 
WHO DID NOT EXECUTE THE ABOVE LICENSES, MAY BE IMPLICATED BY THE 
IMPLEMENTATION OF OR COMPLIANCE WITH THIS SPECIFICATION. OCP IS NOT 
RESPONSIBLE FOR IDENTIFYING RIGHTS FOR WHICH A LICENSE MAY BE REQUIRED 
IN ORDER TO IMPLEMENT THIS SPECIFICATION.  THE ENTIRE RISK AS TO 
IMPLEMENTING OR OTHERWISE USING THE SPECIFICATION IS ASSUMED BY YOU. IN 
NO EVENT WILL OCP BE LIABLE TO YOU FOR ANY MONETARY DAMAGES WITH 
RESPECT TO ANY CLAIMS RELATED TO, OR ARISING OUT OF YOUR USE OF THIS 
SPECIFICATION, INCLUDING BUT NOT LIMITED TO ANY LIABILITY FOR LOST PROFITS 
OR ANY CONSEQUENTIAL, INCIDENTAL, INDIRECT, SPECIAL OR PUNITIVE DAMAGES 
OF ANY CHARACTER FROM ANY CAUSES OF ACTION OF ANY KIND WITH RESPECT TO 
THIS SPECIFICATION, WHETHER BASED ON BREACH OF CONTRACT, TORT 
(INCLUDING NEGLIGENCE), OR OTHERWISE, AND EVEN IF OCP HAS BEEN ADVISED OF 
THE POSSIBILITY OF SUCH DAMAGE. 
 
3.2. Acknowledgements 
The OCP-TAP RCB specification is the outcome of a collaborative effort of OCP-TAP members 
and contributors.  
 
OCP-TAP would like to acknowledge the following members and companies for their 
contributions  
 
• Charlie Ferreira, Furuno Electric 
• Tomasz Widomski, Elproma  
• Wim Rouwet, NXP 
• Jos Prakash Arakkaparambil Vacko, u-blox 
• Samuli Pietilä, u-blox 
• Nobuyasu Shiga, Individual Contributor  
• Ahmad Byagowi, Meta 
• Armando Julies Pinales, Meta 
• Julian St. James, Meta 
• Elad Wind, NVIDIA 
  



Open Compute Project   •   TAP Receiver Carrier Board (RCB) 
Date:  January 2023         Page 6 
4. Compliance with OCP Tenets  
The RCB Form Factor complies to the following OCP (4 out of 5) tenets.  
The ideals behind open sourcing stipulate that everyone benefits when we share and work 
together. Any open-source project is designed to promote sharing of design elements with peers 
and to help them understand and adopt those contributions.  
4.1. Openness 
The RCB takes one step into modularity of the OCP-TAP Time-Card, by allowing a modular 
interchangeable GNSS receivers to be easily provisioned into Time Cards.  
This standard modular form factor allows for more vendors to drive their innovation and make 
time-aware data centers ubiquitous  
4.2. Efficiency  
With this modularity Time-Cards functionality such as hold-over and precision can be designed 
and qualified separately from the GNSS receiver, and allow for parallel technological cycles to 
happen simultaneously. Technical improvements in the RCB do not mandate a change in the 
Time Card.  
4.3. Impact 
The RCB improves the time-to-market advantage of GNSS innovations, such as the ability to 
add support for new constellations, for dual-band constellation receivers, and more.  
4.4. Scale 
With the interest generated around Time Card standard, we expect multiple vendors to design 
and obtain product recognition (OCP Accepted™ or OCP Inspired™) for a thriving marketplace 
of Time-Cards and RCBs at scale. 
 
  



Open Compute Project   •   TAP Receiver Carrier Board (RCB) 
Date:  January 2023         Page 7 
5. Physical Specifications  
The RCB module footprint, I/O and mechanical requirements are defined for interoperability with 
the OCP-TAP Time-Card specification.  
 
The RCB consists of a 67.25 mm x 31.75 mm PCB.  
5.1. Labeling  
Labels will contain information about the part number and the serial number. The serial 
number indicates the initial time of manufacture. 
5.2. I/O  
The RCB contains the following I/O interfaces:  
1. Time-Card Board Connector  
2. Antenna Coax SMA or SMB Connector  
3. LED indicators are optional and per vendor’s implementation  
5.3. Board Connector – Pinout 
The Time-Card Board Connector is a standard 8-pin header which holds the main functions of 
the RCB  
1. UART – ToD from the GNSS communication 
2. PPS Out  
 
Pin # Name Type Description 
1 VCC_ANT Power Antenna Power Supply, 3v3 to 5v with Max 100mA 
2 VCC Power Receiver Power, 3v3 with Max 200mA 
3 TXD Output UART TDX, LVCMOS 
4 RST Input Hardware Reset 
5 RXD Input UART RXD, LVCMOS 
6 TP1 Output Time Pulse (1-PPS recommended), LVCMOS 
7 TP2 Output / Input Time Pulse (output, input, unused or specific), 
LVCMOS 
8 GND Power Power Return, Ground 
5.4. Foot Print and Layout 
This defines the mechanical form factor and layout of the RCB.  
Specifically, we call out the placement of  
1. Antenna connector [        ] 
2. Time-Card Board Connector [J1] 
3. Time-Card mounting holes 
 
We call out 4 screw holes, their locations and dimensions are mandatory. Apply grounded keep-
out areas for the screw holes  
 



Open Compute Project   •   TAP Receiver Carrier Board (RCB) 
Date:  January 2023         Page 8 
5.4.1. Bottom View  
he grayed (to be sketched) zone defines a height-limit that shall not exceed TBD mm, and is 
meant to allow usability of the real estate on the mating Time Card  
 
 
5.4.2. Side View 
 
 
 
 
6. Hardware Management 
We intentionally leave the hardware management of the RCB for the vendors to define and 
implement. This will cover programming of the ICs, diagnostics, etc.  
7. Version Table 
 
67.25mm 
60.5mm 
10.75mm 
 
 
J1 
 
8  7 
6  5 
4  3 
2  1 
3.1mm 
26mm 
 31.75mm 
67.25mm 
60.5mm 
J1 
16.50mm 
7mm 
8mm 
4mm 
Time-Card  
Board Connector 



Open Compute Project   •   TAP Receiver Carrier Board (RCB) 
Date:  January 2023         Page 9 
Date Version # Author Description 
January 23, 2023 0.1 OCP-TAP First draft 
    
8. References 
[1] OCP-TAP Time Card specification and all other related OCP-TAP specs can be found here 
https://github.com/opencomputeproject/Time-Appliance-Project    
 
[2] Assortments of RCBs  
 


Open Compute Project   •   TAP Receiver Carrier Board (RCB) 
Date:  January 2023         Page 10 
  



Open Compute Project   •   TAP Receiver Carrier Board (RCB) 
Date:  January 2023         Page 11 
Appendix A  - Checklist  for IC approval  
of this Specification (to be completed by contributor(s) of this Spec) 
Complete all the checklist items in the table with links to the section where it is described in this 
spec or an external document . 
Item  Status or Details Link to detailed explanation 
Is this contribution entered 
into the OCP Contribution 
Portal? 
Yes or No If no, please state reason. 
Was it approved in the OCP 
Contribution Portal? 
Yes or No If no, please state reason. 
Is there a Supplier(s) that is 
building a product based on 
this Spec? (Supplier must be 
an OCP Solution Provider) 
Yes or No List Supplier Name(s) 
Will Supplier(s) have the 
product available for 
GENERAL AVAILABILITY 
within 120 days? 
Yes or No If more time is required, 
please state the timeline and 
reason for extension request. 
 
Please have each Supplier fill 
out Appendix B.  
  



Open Compute Project   •   TAP Receiver Carrier Board (RCB) 
Date:  January 2023         Page 12 
Appendix B-__ <supplier name>  - OCP Supplier Information and Hardware 
Product Recognition Checklist 
(to be provided by each  supplier seeking OCP recognition for a Hardware Product based on 
this specification)  
 
Company: 
Contact Info: 
 
Product Name: 
Product SKU#:  
Link to Product Landing Page: 
 
 
The following is needed for OCP hardware product recognition:  
 
For OCP Inspired™   
● All Suppliers must be a Silver, Gold or Platinum Member. 
● Declare product is 100% compliant with specification 
● Complete the OCP Inspired™ Product Recognition Checklist, which includes hardware 
management conformance checks and security profile. 
 
 
For OCP Accepted™  
● All Suppliers must be an OCP Member. All corporate membership levels are eligible.  
● Complete the OCP Accepted™ Product Recognition Checklist, which includes hardware 
management conformance checks, security profile and open system firmware 
conformance checks. 
● Submit a design package meeting OCP Hardware Design Guideline Contribution 
Checklist (if not already submitted by the contributor). If already submitted, declare the 
product is 100% compliant with the design package. 
● Submit a  firmware package including a firmware image, build scripts, documentation, 
test results and a tool that verifies modifications 
● Submit the BMC source code, if applicable to product type 
 
Please complete the OCP Inspired™ Product Recognition Submission Checklist or OCP 
Accepted™ Product Recognition Checklist and the following table. 
 
 
  
 
 
Item  Details Links 
Which product recognition? OCP Accepted™ or OCP 
Inspired™ 
Provide link for the 
appropriate Product Checklist 



Open Compute Project   •   TAP Receiver Carrier Board (RCB) 
Date:  January 2023         Page 13 
If OCP Accepted™, who 
provided the Design 
Package? 
 Link to OCP Contribution 
Database 
Where can a potential 
adopter purchase the 
product? 
 
 Link to OCP Marketplace  
  



Open Compute Project   •   TAP Receiver Carrier Board (RCB) 
Date:  January 2023         Page 14 
Appendix C -  Contribution Process FAQs 
 
As a contributor to a hardware specification, here are some questions that often come up. 
 
 
Q1.  What type of hardware specification am I contributing to OCP? Is it any of the below? 
a. base specification for a de-facto standard (new standard with no hardware 
product on the horizon) 
b. base specification for an intended physical <hardware product type> (product 
may be coming but within the next 1-2 years) 
c. modification of an existing specification (state which existing spec is being 
modified)  
i. either a complete revision update or  
ii. a minor version update 
d. design spec (based on an existing base specification) with more refined design 
details (product coming in 12-15months) 
e. a detailed specification for a <hardware product type> for a very specific product 
being available in 3-6months of approval of this Spec 
f. If none of the above, please contact OCP Staff for better direction. 
Q2.  How do I know if what I am contributing will be accepted by OCP? 
a. Before contributing any specifications, please contact either OCP Staff (Archna 
Haylock or Michael Schill) or the Project Lead for the Project that best represents 
your contribution. For example, if you are contributing a Server Specification, 
please contact one of the Server Project Leads. You can see all the Projects 
here.  
b. They will help you with your contribution and help you navigate the process. 
Q3.  What is the contribution process for my hardware spec? 
a. Follow the flow for your spec type here.  
b. This flow is subject to change so please check with the OCP Staff for more 
information or any questions. 
Q4. What if my spec is not developed yet and I want to collaborate with other companies? 
a. Please contact either OCP Staff (Archna Haylock or Michael Schill) or the Project 
Lead for the Project that best represents your contribution.  
b. They will help you find other collaborators and help you with the contribution 
process for a multi-party contribution. 
Q5. I have a question on the Contribution License Agreement.  
a. Please contact OCP Staff and we can help you with questions. 
Q6. Do I need to have a product in order to contribute a spec? 
a. Please see Q1. Some types of specs do not require an immediate product. Some 
do. Please work with the OCP Staff on better direction on your specification type. 